# BASEBOARD_FAB2 (Tioga Pass) — schematic netlist excerpt (pin names and nets, part order shuffled) for the footprints in the layout excerpt that follows; sources: Cadence DE-HDL packaged netlist, KiCad conversion of Wiwynn_Tioga_Pass_MB.brd

R7F17  RES  1.0K 0.1% CHIP  pkg 0402  page 231 : A = VSENSE_PVPP_ABC ; B = VR_COMP_PVPP_ABC
R9B12  RES  1.00K 1% CHIP  pkg 0402  page 113 : A = P1V8_MCP_CPU0 ; B = JTAG_MCP_MUX_TDO
R10W1  RES  100.0 1% CHIP  pkg 0402  page 251 : A = PUMP_TACH0 ; B = PUMP_TACH_R

(kicad_pcb
	(version 20260206)
	(generator "pcbnew")
	(generator_version "10.0")
	(general
		(thickness 1.6)
		(legacy_teardrops no)
	)
	(paper "A4")
	(title_block
		(title "Wiwynn_Tioga_Pass_MB.brd")
		(comment 1 "Tioga Pass / footprints 831-833 of 4770")
	)
	(layers
		(0 "F.Cu" signal "TOP")
		(4 "In1.Cu" signal "L2GND")
		(6 "In2.Cu" signal "L3")
		(8 "In3.Cu" signal "L4GND")
		(10 "In4.Cu" signal "L5")
		(12 "In5.Cu" signal "L6GND")
		(14 "In6.Cu" signal "L7VCC")
		(16 "In7.Cu" signal "L8VCC")
		(18 "In8.Cu" signal "L9GND")
		(20 "In9.Cu" signal "L10")
		(22 "In10.Cu" signal "L11GND")
		(24 "In11.Cu" signal "L12")
		(26 "In12.Cu" signal "L13GND")
		(2 "B.Cu" signal "BOTTOM")
		(9 "F.Adhes" user "F.Adhesive")
		(11 "B.Adhes" user "B.Adhesive")
		(13 "F.Paste" user "Package Geometry/Pastemask Top")
		(15 "B.Paste" user "Package Geometry/Pastemask Bottom")
		(5 "F.SilkS" user "Ref Des/Silkscreen Top")
		(7 "B.SilkS" user "Ref Des/Silkscreen Bottom")
		(1 "F.Mask" user "Board Geometry/Soldermask Top")
		(3 "B.Mask" user "Board Geometry/Soldermask Bottom")
		(17 "Dwgs.User" user "User.Drawings")
		(19 "Cmts.User" user "User.Comments")
		(21 "Eco1.User" user "User.Eco1")
		(23 "Eco2.User" user "User.Eco2")
		(25 "Edge.Cuts" user "Board Geometry/Outline")
		(27 "Margin" user)
		(31 "F.CrtYd" user "Package Geometry/Place Bound Top")
		(29 "B.CrtYd" user "Package Geometry/Place Bound Bottom")
		(35 "F.Fab" user "Ref Des/Assembly Top")
		(33 "B.Fab" user "Ref Des/Assembly Bottom")
	)
	(footprint ""
		(layer "F.Cu")
		(at 335.788 -23.241)
		(property "Reference" "R7F17"
			(at 0 0 0)
			(layer "F.SilkS")
			(hide yes)
			(effects
				(font
					(size 1.27 1.27)
				)
			)
		)
		(property "Value" ""
			(at 0 0 0)
			(layer "F.Fab")
			(effects
				(font
					(size 1.27 1.27)
				)
			)
		)
		(duplicate_pad_numbers_are_jumpers no)
		(fp_poly
			(pts
				(xy -0.2794 -0.1016) (xy 0.2794 -0.1016) (xy 0.2794 0.9906) (xy -0.2794 0.9906)
			)
			(stroke
				(width 0)
				(type default)
			)
			(fill no)
			(layer "F.CrtYd")
		)
		(fp_line
			(start -0.2794 -0.1016)
			(end -0.2794 0.9906)
			(stroke
				(width 0.1)
				(type default)
			)
			(layer "F.Fab")
		)
		(fp_line
			(start -0.2794 0.9906)
			(end 0.2794 0.9906)
			(stroke
				(width 0.1)
				(type default)
			)
			(layer "F.Fab")
		)
		(fp_line
			(start 0.2794 -0.1016)
			(end -0.2794 -0.1016)
			(stroke
				(width 0.1)
				(type default)
			)
			(layer "F.Fab")
		)
		(fp_line
			(start 0.2794 0.9906)
			(end 0.2794 -0.1016)
			(stroke
				(width 0.1)
				(type default)
			)
			(layer "F.Fab")
		)
		(pad "1" smd rect
			(at 0 0)
			(size 0.508 0.508)
			(layers "F.Cu" "F.Mask" "F.Paste")
			(net "VSENSE_PVPP_ABC")
		)
		(pad "2" smd rect
			(at 0 0.889)
			(size 0.508 0.508)
			(layers "F.Cu" "F.Mask" "F.Paste")
			(net "VR_COMP_PVPP_ABC")
		)
		(zone
			(layer "F.Cu")
			(hatch none 0.5)
			(connect_pads
				(clearance 0)
			)
			(min_thickness 0.25)
			(keepout
				(tracks allowed)
				(vias not_allowed)
				(pads allowed)
				(copperpour not_allowed)
				(footprints allowed)
			)
			(placement
				(enabled no)
				(sheetname "")
			)
			(fill
				(thermal_gap 0.5)
				(thermal_bridge_width 0.5)
				(island_removal_mode 0)
			)
			(polygon
				(pts
					(xy 335.534 -22.987) (xy 336.042 -22.987) (xy 336.042 -22.606) (xy 335.534 -22.606)
				)
			)
		)
		(zone
			(layer "F.Cu")
			(hatch none 0.5)
			(connect_pads
				(clearance 0)
			)
			(min_thickness 0.25)
			(keepout
				(tracks not_allowed)
				(vias allowed)
				(pads allowed)
				(copperpour not_allowed)
				(footprints allowed)
			)
			(placement
				(enabled no)
				(sheetname "")
			)
			(fill
				(thermal_gap 0.5)
				(thermal_bridge_width 0.5)
				(island_removal_mode 0)
			)
			(polygon
				(pts
					(xy 335.534 -22.606) (xy 336.042 -22.606) (xy 336.042 -22.987) (xy 335.534 -22.987)
				)
			)
		)
	)
	(footprint ""
		(layer "F.Cu")
		(at 467.36 -132.715 180)
		(property "Reference" "R9B12"
			(at 0 0 180)
			(layer "F.SilkS")
			(hide yes)
			(effects
				(font
					(size 1.27 1.27)
				)
			)
		)
		(property "Value" ""
			(at 0 0 180)
			(layer "F.Fab")
			(effects
				(font
					(size 1.27 1.27)
				)
			)
		)
		(duplicate_pad_numbers_are_jumpers no)
		(fp_poly
			(pts
				(xy -0.2794 -0.1016) (xy 0.2794 -0.1016) (xy 0.2794 0.9906) (xy -0.2794 0.9906)
			)
			(stroke
				(width 0)
				(type default)
			)
			(fill no)
			(layer "F.CrtYd")
		)
		(fp_line
			(start 0.2794 0.9906)
			(end 0.2794 -0.1016)
			(stroke
				(width 0.1)
				(type default)
			)
			(layer "F.Fab")
		)
		(fp_line
			(start 0.2794 -0.1016)
			(end -0.2794 -0.1016)
			(stroke
				(width 0.1)
				(type default)
			)
			(layer "F.Fab")
		)
		(fp_line
			(start -0.2794 0.9906)
			(end 0.2794 0.9906)
			(stroke
				(width 0.1)
				(type default)
			)
			(layer "F.Fab")
		)
		(fp_line
			(start -0.2794 -0.1016)
			(end -0.2794 0.9906)
			(stroke
				(width 0.1)
				(type default)
			)
			(layer "F.Fab")
		)
		(pad "1" smd rect
			(at 0 0 180)
			(size 0.508 0.508)
			(layers "F.Cu" "F.Mask" "F.Paste")
			(net "P1V8_MCP_CPU0")
		)
		(pad "2" smd rect
			(at 0 0.889 180)
			(size 0.508 0.508)
			(layers "F.Cu" "F.Mask" "F.Paste")
			(net "JTAG_MCP_MUX_TDO")
		)
		(zone
			(layer "F.Cu")
			(hatch none 0.5)
			(connect_pads
				(clearance 0)
			)
			(min_thickness 0.25)
			(keepout
				(tracks not_allowed)
				(vias allowed)
				(pads allowed)
				(copperpour not_allowed)
				(footprints allowed)
			)
			(placement
				(enabled no)
				(sheetname "")
			)
			(fill
				(thermal_gap 0.5)
				(thermal_bridge_width 0.5)
				(island_removal_mode 0)
			)
			(polygon
				(pts
					(xy 467.614 -133.35) (xy 467.106 -133.35) (xy 467.106 -132.969) (xy 467.614 -132.969)
				)
			)
		)
		(zone
			(layer "F.Cu")
			(hatch none 0.5)
			(connect_pads
				(clearance 0)
			)
			(min_thickness 0.25)
			(keepout
				(tracks allowed)
				(vias not_allowed)
				(pads allowed)
				(copperpour not_allowed)
				(footprints allowed)
			)
			(placement
				(enabled no)
				(sheetname "")
			)
			(fill
				(thermal_gap 0.5)
				(thermal_bridge_width 0.5)
				(island_removal_mode 0)
			)
			(polygon
				(pts
					(xy 467.614 -132.969) (xy 467.106 -132.969) (xy 467.106 -133.35) (xy 467.614 -133.35)
				)
			)
		)
	)
	(footprint ""
		(layer "F.Cu")
		(at 437.388 -19.4945)
		(property "Reference" "R10W1"
			(at -0.8382 -0.67818 0)
			(unlocked yes)
			(layer "F.SilkS")
			(effects
				(font
					(size 0.4064 0.254)
					(thickness 0.1524)
				)
				(justify left)
			)
		)
		(property "Value" ""
			(at 0 0 0)
			(layer "F.Fab")
			(effects
				(font
					(size 1.27 1.27)
				)
			)
		)
		(duplicate_pad_numbers_are_jumpers no)
		(fp_poly
			(pts
				(xy -0.2794 -0.1016) (xy 0.2794 -0.1016) (xy 0.2794 0.9906) (xy -0.2794 0.9906)
			)
			(stroke
				(width 0)
				(type default)
			)
			(fill no)
			(layer "F.CrtYd")
		)
		(fp_line
			(start -0.2794 -0.1016)
			(end -0.2794 0.9906)
			(stroke
				(width 0.1)
				(type default)
			)
			(layer "F.Fab")
		)
		(fp_line
			(start -0.2794 0.9906)
			(end 0.2794 0.9906)
			(stroke
				(width 0.1)
				(type default)
			)
			(layer "F.Fab")
		)
		(fp_line
			(start 0.2794 -0.1016)
			(end -0.2794 -0.1016)
			(stroke
				(width 0.1)
				(type default)
			)
			(layer "F.Fab")
		)
		(fp_line
			(start 0.2794 0.9906)
			(end 0.2794 -0.1016)
			(stroke
				(width 0.1)
				(type default)
			)
			(layer "F.Fab")
		)
		(pad "1" smd rect
			(at 0 0)
			(size 0.508 0.508)
			(layers "F.Cu" "F.Mask" "F.Paste")
			(net "PUMP_TACH0")
		)
		(pad "2" smd rect
			(at 0 0.889)
			(size 0.508 0.508)
			(layers "F.Cu" "F.Mask" "F.Paste")
			(net "PUMP_TACH_R")
		)
		(zone
			(layer "F.Cu")
			(hatch none 0.5)
			(connect_pads
				(clearance 0)
			)
			(min_thickness 0.25)
			(keepout
				(tracks allowed)
				(vias not_allowed)
				(pads allowed)
				(copperpour not_allowed)
				(footprints allowed)
			)
			(placement
				(enabled no)
				(sheetname "")
			)
			(fill
				(thermal_gap 0.5)
				(thermal_bridge_width 0.5)
				(island_removal_mode 0)
			)
			(polygon
				(pts
					(xy 437.134 -19.2405) (xy 437.642 -19.2405) (xy 437.642 -18.8595) (xy 437.134 -18.8595)
				)
			)
		)
		(zone
			(layer "F.Cu")
			(hatch none 0.5)
			(connect_pads
				(clearance 0)
			)
			(min_thickness 0.25)
			(keepout
				(tracks not_allowed)
				(vias allowed)
				(pads allowed)
				(copperpour not_allowed)
				(footprints allowed)
			)
			(placement
				(enabled no)
				(sheetname "")
			)
			(fill
				(thermal_gap 0.5)
				(thermal_bridge_width 0.5)
				(island_removal_mode 0)
			)
			(polygon
				(pts
					(xy 437.134 -18.8595) (xy 437.642 -18.8595) (xy 437.642 -19.2405) (xy 437.134 -19.2405)
				)
			)
		)
	)
)
